(kicad_pcb
	(version 20221018)
	(generator pcbnew)
	(general
    (thickness 1.7403)
  )
	(paper "A4")
	(title_block
    (title "Data Center RDIMM DDR4 Tester")
    (date "2024-09-30")
    (rev "1.2.4")
		(comment 9 "footprints 20-27 of 690")
	)
	(layers
    (0 "F.Cu" signal)
    (1 "In1.Cu" power)
    (2 "In2.Cu" signal)
    (3 "In3.Cu" power)
    (4 "In4.Cu" power)
    (5 "In5.Cu" signal)
    (6 "In6.Cu" power)
    (7 "In7.Cu" signal)
    (8 "In8.Cu" power)
    (9 "In9.Cu" signal)
    (10 "In10.Cu" power)
    (31 "B.Cu" signal)
    (32 "B.Adhes" user "B.Adhesive")
    (33 "F.Adhes" user "F.Adhesive")
    (34 "B.Paste" user)
    (35 "F.Paste" user)
    (36 "B.SilkS" user "B.Silkscreen")
    (37 "F.SilkS" user "F.Silkscreen")
    (38 "B.Mask" user)
    (39 "F.Mask" user)
    (40 "Dwgs.User" user "User.Drawings")
    (41 "Cmts.User" user "User.Comments")
    (42 "Eco1.User" user "User.Eco1")
    (43 "Eco2.User" user "User.Eco2")
    (44 "Edge.Cuts" user)
    (45 "Margin" user)
    (46 "B.CrtYd" user "B.Courtyard")
    (47 "F.CrtYd" user "F.Courtyard")
    (48 "B.Fab" user)
    (49 "F.Fab" user)
  )
	(footprint "data-center-rdimm-ddr4-tester-footprints:PowerDI5" (layer "F.Cu")
    (at 127.4 123.9 90)
    (property "Author" "Antmicro")
    (property "License" "Apache-2.0")
    (property "MPN" "PDS760-13")
    (property "Manufacturer" "Diodes Incorporated")
    (property "Sheetfile" "supply.kicad_sch")
    (property "Sheetname" "Supply")
    (property "ki_description" "PDS760 Series 60 V 7 A Surface Mount Schottky Barrier Rectifier - PowerDI-5")
    (property "ki_keywords" "PDS760 Series 60 V 7 A Surface Mount Schottky Barrier Rectifier - PowerDI-5")
    (attr smd)
    (fp_text reference "D2" (at -3.72 1.71 180) (layer "F.SilkS")
        (effects (font (size 0.7 0.7) (thickness 0.15)) (justify left bottom))
    )
    (fp_text value "PDS760" (at 0 3.4 90) (layer "F.Fab") hide
        (effects (font (size 0.7 0.7) (thickness 0.15)) (justify right bottom))
    )
    (fp_text user "${REFERENCE}" (at -3.302 18.527 90) (layer "F.Fab") hide
        (effects (font (size 0.7 0.7) (thickness 0.15)) (justify left bottom))
    )
    (fp_text user "License: Apache-2.0" (at -3.302 20.928 90) (layer "F.Fab") hide
        (effects (font (size 0.7 0.7) (thickness 0.15)) (justify left bottom))
    )
    (fp_text user "Author: Antmicro" (at -3.302 19.728 90) (layer "F.Fab") hide
        (effects (font (size 0.7 0.7) (thickness 0.15)) (justify left bottom))
    )
    (fp_line (start -2.7 -2) (end 2.7 -2)
      (stroke (width 0.12) (type solid)) (layer "F.SilkS"))
    (fp_line (start -2.7 -1.8) (end -2.7 -2)
      (stroke (width 0.12) (type solid)) (layer "F.SilkS"))
    (fp_line (start -2.7 2.023) (end -2.7 1.823)
      (stroke (width 0.12) (type solid)) (layer "F.SilkS"))
    (fp_line (start 2.7 -2) (end 2.7 -1.8)
      (stroke (width 0.12) (type solid)) (layer "F.SilkS"))
    (fp_line (start 2.7 1.823) (end 2.7 2.023)
      (stroke (width 0.12) (type solid)) (layer "F.SilkS"))
    (fp_line (start 2.7 2.023) (end -2.7 2.023)
      (stroke (width 0.12) (type solid)) (layer "F.SilkS"))
    (fp_rect (start -3.702 -2.3) (end 3.7 2.3)
      (stroke (width 0.05) (type solid)) (fill none) (layer "F.CrtYd"))
    (pad "A" smd roundrect (at -2.862 -0.94 180) (size 1.39 1.4) (layers "F.Cu" "F.Paste" "F.Mask") (roundrect_rratio 0.25)
      (net 9 "GND") (pinfunction "A") (pintype "passive"))
    (pad "A" smd roundrect (at -2.862 0.941) (size 1.39 1.4) (layers "F.Cu" "F.Paste" "F.Mask") (roundrect_rratio 0.25)
      (net 9 "GND") (pinfunction "A") (pintype "passive"))
    (pad "C" smd roundrect (at 1.1 0) (size 3.36 4.86) (layers "F.Cu" "F.Paste" "F.Mask") (roundrect_rratio 0.05)
      (net 73 "Net-(IC1-SW)") (pinfunction "C") (pintype "passive"))
  )
	(footprint "data-center-rdimm-ddr4-tester-footprints:L_WE-PDF" (layer "F.Cu")
    (at 126.911328 113.872157 90)
    (property "Author" "Antmicro")
    (property "IMax" "")
    (property "ISat" "")
    (property "License" "Apache-2.0")
    (property "MPN" "7447798720")
    (property "Manufacturer" "Würth Elektronik")
    (property "Sheetfile" "supply.kicad_sch")
    (property "Sheetname" "Supply")
    (property "Size" "10.2x10.2")
    (property "Val" "7u2/7.9A")
    (attr smd)
    (fp_text reference "L6" (at -6.157843 3.928672) (layer "F.SilkS")
        (effects (font (size 0.7 0.7) (thickness 0.15)) (justify left bottom))
    )
    (fp_text value "L_7u2_7.9A_WE-PDF" (at 0 6.6 270) (layer "F.Fab") hide
        (effects (font (size 0.7 0.7) (thickness 0.15)) (justify left bottom))
    )
    (fp_text user "License: Apache-2.0" (at -5.601 8.6 90) (layer "F.Fab") hide
        (effects (font (size 0.7 0.7) (thickness 0.15)) (justify left bottom))
    )
    (fp_text user "Author: Antmicro" (at -5.601 9.8 90) (layer "F.Fab") hide
        (effects (font (size 0.7 0.7) (thickness 0.15)) (justify left bottom))
    )
    (fp_text user "${REFERENCE}" (at -5.601 11 90) (layer "F.Fab") hide
        (effects (font (size 0.7 0.7) (thickness 0.15)) (justify left bottom))
    )
    (fp_line (start -5.202 -5.202) (end 4.099 -5.202)
      (stroke (width 0.15) (type solid)) (layer "F.SilkS"))
    (fp_line (start -5.202 -2) (end -5.202 -5.202)
      (stroke (width 0.15) (type solid)) (layer "F.SilkS"))
    (fp_line (start -5.202 5.2) (end -5.202 1.999)
      (stroke (width 0.15) (type solid)) (layer "F.SilkS"))
    (fp_line (start 4.099 -5.202) (end 5.2 -4.1)
      (stroke (width 0.15) (type solid)) (layer "F.SilkS"))
    (fp_line (start 5.2 -4.1) (end 5.2 -2)
      (stroke (width 0.15) (type solid)) (layer "F.SilkS"))
    (fp_line (start 5.2 1.999) (end 5.2 4.2)
      (stroke (width 0.15) (type solid)) (layer "F.SilkS"))
    (fp_line (start 5.2 4.2) (end 5.2 5.2)
      (stroke (width 0.15) (type solid)) (layer "F.SilkS"))
    (fp_line (start 5.2 5.2) (end -5.202 5.2)
      (stroke (width 0.15) (type solid)) (layer "F.SilkS"))
    (fp_rect (start -5.601 -5.601) (end 5.599 5.599)
      (stroke (width 0.05) (type solid)) (fill none) (layer "F.CrtYd"))
    (pad "1" smd rect (at -4.1 0 180) (size 3.4 2.4) (layers "F.Cu" "F.Paste" "F.Mask")
      (net 73 "Net-(IC1-SW)") (pintype "passive"))
    (pad "2" smd rect (at 4.099 0 180) (size 3.4 2.4) (layers "F.Cu" "F.Paste" "F.Mask")
      (net 104 "VCC5V0") (pintype "passive"))
  )
	(footprint "data-center-rdimm-ddr4-tester-footprints:Testpoint_smd_1mm" (layer "F.Cu")
    (at 109.966328 92.580008 90)
    (property "Author" "Antmicro")
    (property "License" "Apache-2.0")
    (property "MPN" "")
    (property "Manufacturer" "")
    (property "Sheetfile" "supply.kicad_sch")
    (property "Sheetname" "Supply")
    (property "ki_description" "Test Point 1mm")
    (attr exclude_from_pos_files)
    (fp_text reference "0V6" (at 0.660008 -1.726328 180) (layer "F.SilkS")
        (effects (font (size 0.7 0.7) (thickness 0.15)) (justify left bottom))
    )
    (fp_text value "TP_1mm_SMD" (at 0 1.4 90) (layer "F.Fab") hide
        (effects (font (size 0.7 0.7) (thickness 0.15)) (justify left bottom))
    )
    (fp_text user "${REFERENCE}" (at -0.5 2.8 90) (layer "F.Fab") hide
        (effects (font (size 0.7 0.7) (thickness 0.15)) (justify left bottom))
    )
    (fp_text user "License: Apache-2.0" (at -0.5 5.2 90) (layer "F.Fab") hide
        (effects (font (size 0.7 0.7) (thickness 0.15)) (justify left bottom))
    )
    (fp_text user "Author: Antmicro" (at -0.5 4 90) (layer "F.Fab") hide
        (effects (font (size 0.7 0.7) (thickness 0.15)) (justify left bottom))
    )
    (pad "1" smd circle (at 0 0 90) (size 1 1) (layers "F.Cu" "F.Mask")
      (net 299 "VCC0V6") (pinfunction "1") (pintype "passive"))
  )
	(footprint "data-center-rdimm-ddr4-tester-footprints:Testpoint_smd_1mm" (layer "F.Cu")
    (at 129.5 97.5 180)
    (property "Author" "Antmicro")
    (property "License" "Apache-2.0")
    (property "MPN" "")
    (property "Manufacturer" "")
    (property "Sheetfile" "supply.kicad_sch")
    (property "Sheetname" "Supply")
    (property "ki_description" "Test Point 1mm")
    (attr exclude_from_pos_files)
    (fp_text reference "2V5" (at 1.05 -1.41 180) (layer "F.SilkS")
        (effects (font (size 0.7 0.7) (thickness 0.15)) (justify left bottom))
    )
    (fp_text value "TP_1mm_SMD" (at 0 1.4 180) (layer "F.Fab") hide
        (effects (font (size 0.7 0.7) (thickness 0.15)) (justify left bottom))
    )
    (fp_text user "${REFERENCE}" (at -0.5 2.8 180) (layer "F.Fab") hide
        (effects (font (size 0.7 0.7) (thickness 0.15)) (justify left bottom))
    )
    (fp_text user "Author: Antmicro" (at -0.5 4 180) (layer "F.Fab") hide
        (effects (font (size 0.7 0.7) (thickness 0.15)) (justify left bottom))
    )
    (fp_text user "License: Apache-2.0" (at -0.5 5.2 180) (layer "F.Fab") hide
        (effects (font (size 0.7 0.7) (thickness 0.15)) (justify left bottom))
    )
    (pad "1" smd circle (at 0 0 180) (size 1 1) (layers "F.Cu" "F.Mask")
      (net 303 "VCC2V5") (pinfunction "1") (pintype "passive"))
  )
	(footprint "data-center-rdimm-ddr4-tester-footprints:L_1210_3225Metric" (layer "F.Cu")
    (at 119.036328 93.247157 180)
    (property "Author" "Antmicro")
    (property "IMax" "")
    (property "ISat" "")
    (property "License" "Apache-2.0")
    (property "MPN" "DFE322512F-R68M=P2")
    (property "Manufacturer" "Murata")
    (property "Sheetfile" "supply.kicad_sch")
    (property "Sheetname" "Supply")
    (property "Size" "3.2x2.5")
    (property "Val" "680n/6.1A")
    (attr smd)
    (fp_text reference "L2" (at 2.056328 1.587157 180) (layer "F.SilkS")
        (effects (font (size 0.7 0.7) (thickness 0.15)) (justify left bottom))
    )
    (fp_text value "L_680n_6.1A_1210" (at 0 2.4 180) (layer "F.Fab") hide
        (effects (font (size 0.7 0.7) (thickness 0.15)) (justify left bottom))
    )
    (fp_text user "Author: Antmicro" (at -2.1 5.15 180) (layer "F.Fab") hide
        (effects (font (size 0.7 0.7) (thickness 0.15)) (justify left bottom))
    )
    (fp_text user "${REFERENCE}" (at -2.1 3.95 180) (layer "F.Fab") hide
        (effects (font (size 0.7 0.7) (thickness 0.15)) (justify left bottom))
    )
    (fp_text user "License: Apache-2.0" (at -2.1 6.35 180) (layer "F.Fab") hide
        (effects (font (size 0.7 0.7) (thickness 0.15)) (justify left bottom))
    )
    (fp_line (start -0.7 -1.4) (end 0.7 -1.4)
      (stroke (width 0.15) (type solid)) (layer "F.SilkS"))
    (fp_line (start -0.7 1.4) (end 0.7 1.4)
      (stroke (width 0.15) (type solid)) (layer "F.SilkS"))
    (fp_rect (start -2.1 -1.5) (end 2.09 1.5)
      (stroke (width 0.05) (type solid)) (fill none) (layer "F.CrtYd"))
    (fp_line (start -1.701 1.35) (end -1.701 -1.351)
      (stroke (width 0.15) (type solid)) (layer "F.Fab"))
    (fp_line (start 1.7 -1.351) (end -1.701 -1.351)
      (stroke (width 0.15) (type solid)) (layer "F.Fab"))
    (fp_line (start 1.7 1.35) (end -1.701 1.35)
      (stroke (width 0.15) (type solid)) (layer "F.Fab"))
    (fp_line (start 1.7 1.35) (end 1.7 -1.351)
      (stroke (width 0.15) (type solid)) (layer "F.Fab"))
    (pad "1" smd rect (at -1.439 0 180) (size 1.24 2.72) (layers "F.Cu" "F.Paste" "F.Mask")
      (net 1 "Net-(U2-SW)") (pintype "passive"))
    (pad "2" smd rect (at 1.439 0 180) (size 1.24 2.72) (layers "F.Cu" "F.Paste" "F.Mask")
      (net 301 "VDD1V2") (pintype "passive"))
  )
	(footprint "data-center-rdimm-ddr4-tester-footprints:Testpoint_smd_1mm" (layer "F.Cu")
    (at 123.136328 80.360008)
    (property "Author" "Antmicro")
    (property "License" "Apache-2.0")
    (property "MPN" "")
    (property "Manufacturer" "")
    (property "Sheetfile" "supply.kicad_sch")
    (property "Sheetname" "Supply")
    (property "ki_description" "Test Point 1mm")
    (attr exclude_from_pos_files)
    (fp_text reference "1V2" (at -1.056328 -0.740008) (layer "F.SilkS")
        (effects (font (size 0.7 0.7) (thickness 0.15)) (justify left bottom))
    )
    (fp_text value "TP_1mm_SMD" (at 0 1.4) (layer "F.Fab") hide
        (effects (font (size 0.7 0.7) (thickness 0.15)) (justify left bottom))
    )
    (fp_text user "License: Apache-2.0" (at -0.5 5.2) (layer "F.Fab") hide
        (effects (font (size 0.7 0.7) (thickness 0.15)) (justify left bottom))
    )
    (fp_text user "Author: Antmicro" (at -0.5 4) (layer "F.Fab") hide
        (effects (font (size 0.7 0.7) (thickness 0.15)) (justify left bottom))
    )
    (fp_text user "${REFERENCE}" (at -0.5 2.8) (layer "F.Fab") hide
        (effects (font (size 0.7 0.7) (thickness 0.15)) (justify left bottom))
    )
    (pad "1" smd circle (at 0 0) (size 1 1) (layers "F.Cu" "F.Mask")
      (net 301 "VDD1V2") (pinfunction "1") (pintype "passive"))
  )
	(footprint "data-center-rdimm-ddr4-tester-footprints:WSON-10_4x4" (layer "F.Cu")
    (at 114.286328 114.422157)
    (property "Author" "Antmicro")
    (property "License" "Apache-2.0")
    (property "MPN" "TPS54561QDPRRQ1")
    (property "Manufacturer" "Texas Instruments")
    (property "Sheetfile" "supply.kicad_sch")
    (property "Sheetname" "Supply")
    (property "ki_description" " 4.5-V to 60-V Input, 5-A, Step-Down DC-DC Converter")
    (attr smd)
    (fp_text reference "IC1" (at 2.423672 -0.712157 180) (layer "F.SilkS")
        (effects (font (size 0.7 0.7) (thickness 0.15)) (justify left bottom))
    )
    (fp_text value "TPS54561QDPRRQ1" (at 0 3.4 180) (layer "F.Fab") hide
        (effects (font (size 0.7 0.7) (thickness 0.15)) (justify left bottom))
    )
    (fp_text user "${REFERENCE}" (at -2.52 5.4) (layer "F.Fab") hide
        (effects (font (size 0.7 0.7) (thickness 0.15)) (justify left bottom))
    )
    (fp_text user "License: Apache-2.0" (at -2.52 7.8) (layer "F.Fab") hide
        (effects (font (size 0.7 0.7) (thickness 0.15)) (justify left bottom))
    )
    (fp_text user "Author: Antmicro" (at -2.52 6.6) (layer "F.Fab") hide
        (effects (font (size 0.7 0.7) (thickness 0.15)) (justify left bottom))
    )
    (fp_line (start -2.1 -2.123) (end -2.1 -1.877)
      (stroke (width 0.15) (type solid)) (layer "F.SilkS"))
    (fp_line (start -2.1 -2.123) (end 2.1 -2.123)
      (stroke (width 0.15) (type solid)) (layer "F.SilkS"))
    (fp_line (start -2.1 2.096) (end -2.1 1.85)
      (stroke (width 0.15) (type solid)) (layer "F.SilkS"))
    (fp_line (start 2.1 -2.123) (end 2.1 -1.877)
      (stroke (width 0.15) (type solid)) (layer "F.SilkS"))
    (fp_line (start 2.1 2.122) (end -2.1 2.122)
      (stroke (width 0.15) (type solid)) (layer "F.SilkS"))
    (fp_line (start 2.1 2.122) (end 2.1 1.876)
      (stroke (width 0.15) (type solid)) (layer "F.SilkS"))
    (fp_circle (center -2.4 -2) (end -2.35 -2)
      (stroke (width 0.15) (type solid)) (fill solid) (layer "F.SilkS"))
    (fp_rect (start -2.57 -2.2) (end 2.469 2.2)
      (stroke (width 0.05) (type solid)) (fill none) (layer "F.CrtYd"))
    (fp_line (start -1.7 -2) (end -2 -1.7)
      (stroke (width 0.15) (type solid)) (layer "F.Fab"))
    (fp_rect (start -2.02 -2) (end 2.02 2)
      (stroke (width 0.15) (type solid)) (fill none) (layer "F.Fab"))
    (pad "1" smd roundrect (at -2.039 -1.603 90) (size 0.356 0.85) (layers "F.Cu" "F.Paste" "F.Mask") (roundrect_rratio 0.25)
      (net 71 "Net-(IC1-BOOT)") (pinfunction "BOOT") (pintype "passive"))
    (pad "2" smd roundrect (at -2.039 -0.804 90) (size 0.356 0.85) (layers "F.Cu" "F.Paste" "F.Mask") (roundrect_rratio 0.25)
      (net 103 "VIN") (pinfunction "VDD") (pintype "passive"))
    (pad "3" smd roundrect (at -2.039 -0.003 90) (size 0.356 0.85) (layers "F.Cu" "F.Paste" "F.Mask") (roundrect_rratio 0.25)
      (net 167 "/Supply/SYS_EN") (pinfunction "EN") (pintype "passive"))
    (pad "4" smd roundrect (at -2.039 0.797 90) (size 0.356 0.85) (layers "F.Cu" "F.Paste" "F.Mask") (roundrect_rratio 0.25)
      (net 53 "Net-(IC1-SS{slash}TR)") (pinfunction "SS/TR") (pintype "passive"))
    (pad "5" smd roundrect (at -2.039 1.596 90) (size 0.356 0.85) (layers "F.Cu" "F.Paste" "F.Mask") (roundrect_rratio 0.25)
      (net 109 "Net-(IC1-RT{slash}CLK)") (pinfunction "RT/CLK") (pintype "passive"))
    (pad "6" smd roundrect (at 1.961 1.596 90) (size 0.356 0.85) (layers "F.Cu" "F.Paste" "F.Mask") (roundrect_rratio 0.25)
      (net 110 "Net-(IC1-FB)") (pinfunction "FB") (pintype "passive"))
    (pad "7" smd roundrect (at 1.961 0.797 90) (size 0.356 0.85) (layers "F.Cu" "F.Paste" "F.Mask") (roundrect_rratio 0.25)
      (net 69 "Net-(IC1-COMP)") (pinfunction "COMP") (pintype "passive"))
    (pad "8" smd roundrect (at 1.961 -0.003 90) (size 0.356 0.85) (layers "F.Cu" "F.Paste" "F.Mask") (roundrect_rratio 0.25)
      (net 9 "GND") (pinfunction "GND") (pintype "power_in"))
    (pad "9" smd roundrect (at 1.961 -0.804 90) (size 0.356 0.85) (layers "F.Cu" "F.Paste" "F.Mask") (roundrect_rratio 0.25)
      (net 73 "Net-(IC1-SW)") (pinfunction "SW") (pintype "passive"))
    (pad "10" smd roundrect (at 1.961 -1.603 90) (size 0.356 0.85) (layers "F.Cu" "F.Paste" "F.Mask") (roundrect_rratio 0.25)
      (net 536 "/Supply/SYS_PWR_GOOD") (pinfunction "PWRGD") (pintype "passive"))
    (pad "11" smd roundrect (at -0.038 -0.003 180) (size 2.6 3) (layers "F.Cu" "F.Paste" "F.Mask") (roundrect_rratio 0.05)
      (net 9 "GND") (pinfunction "GND") (pintype "passive"))
  )
	(footprint "data-center-rdimm-ddr4-tester-footprints:R_0402_1005Metric" (layer "F.Cu")
    (at 116.4 99.1 90)
    (descr "Resistor SMD 0402")
    (tags "resistor SMD 0402")
    (property "Author" "Antmicro")
    (property "Current" "1A")
    (property "License" "Apache-2.0")
    (property "MPN" "ERJ2GE0R00X")
    (property "Manufacturer" "Panasonic")
    (property "Sheetfile" "supply.kicad_sch")
    (property "Sheetname" "Supply")
    (property "Tolerance" "")
    (property "Val" "0R")
    (property "ki_description" "0R resistor in 0402 package with unspecified tolerance")
    (attr smd)
    (fp_text reference "R42" (at 0.09 -1.6 90) (layer "F.SilkS")
        (effects (font (size 0.7 0.7) (thickness 0.15)) (justify left bottom))
    )
    (fp_text value "R_0R_0402" (at 0 1.4 90) (layer "F.Fab") hide
        (effects (font (size 0.7 0.7) (thickness 0.15)) (justify left bottom))
    )
    (fp_text user "License: Apache-2.0" (at -0.95 5.169 90) (layer "F.Fab") hide
        (effects (font (size 0.7 0.7) (thickness 0.15)) (justify left bottom))
    )
    (fp_text user "${REFERENCE}" (at -0.95 3.168 90) (layer "F.Fab") hide
        (effects (font (size 0.7 0.7) (thickness 0.15)) (justify left bottom))
    )
    (fp_text user "Author: Antmicro" (at -0.95 4.169 90) (layer "F.Fab") hide
        (effects (font (size 0.7 0.7) (thickness 0.15)) (justify left bottom))
    )
    (fp_rect (start -0.93 -0.47) (end 0.93 0.47)
      (stroke (width 0.05) (type solid)) (fill none) (layer "F.CrtYd"))
    (fp_rect (start -0.5 -0.25) (end 0.5 0.25)
      (stroke (width 0.15) (type solid)) (fill none) (layer "F.Fab"))
    (pad "1" smd roundrect (at -0.485 0 90) (size 0.59 0.64) (layers "F.Cu" "F.Paste" "F.Mask") (roundrect_rratio 0.25)
      (net 616 "Net-(U2-VTTSNS)") (pintype "passive"))
    (pad "2" smd roundrect (at 0.485 0 90) (size 0.59 0.64) (layers "F.Cu" "F.Paste" "F.Mask") (roundrect_rratio 0.25)
      (net 299 "VCC0V6") (pintype "passive"))
  )
)
